(kicad_pcb
	(version 20260206)
	(generator "pcbnew")
	(generator_version "10.0")
	(general
		(thickness 1.6)
		(legacy_teardrops no)
	)
	(paper "A4")
	(title_block
		(title "03242023_DA0F0TMBIJ0_F0T_Motherboard_J_brd_V01_OCP.brd")
		(comment 1 "Grand Teton / footprints 403-408 of 6105")
	)
	(layers
		(0 "F.Cu" signal "TOP")
		(4 "In1.Cu" signal "GND")
		(6 "In2.Cu" signal "IN1")
		(8 "In3.Cu" signal "GND1")
		(10 "In4.Cu" signal "IN2")
		(12 "In5.Cu" signal "GND2")
		(14 "In6.Cu" signal "IN3")
		(16 "In7.Cu" signal "GND3")
		(18 "In8.Cu" signal "VCC")
		(20 "In9.Cu" signal "VCC1")
		(22 "In10.Cu" signal "GND4")
		(24 "In11.Cu" signal "IN4")
		(26 "In12.Cu" signal "GND5")
		(28 "In13.Cu" signal "IN5")
		(30 "In14.Cu" signal "GND6")
		(32 "In15.Cu" signal "IN6")
		(34 "In16.Cu" signal "GND7")
		(2 "B.Cu" signal "BOTTOM")
		(9 "F.Adhes" user "F.Adhesive")
		(11 "B.Adhes" user "B.Adhesive")
		(13 "F.Paste" user "Package Geometry/Pastemask Top")
		(15 "B.Paste" user "Package Geometry/Pastemask Bottom")
		(5 "F.SilkS" user "Ref Des/Silkscreen Top")
		(7 "B.SilkS" user "Ref Des/Silkscreen Bottom")
		(1 "F.Mask" user "Board Geometry/Soldermask Top")
		(3 "B.Mask" user "Board Geometry/Soldermask Bottom")
		(17 "Dwgs.User" user "User.Drawings")
		(19 "Cmts.User" user "User.Comments")
		(21 "Eco1.User" user "User.Eco1")
		(23 "Eco2.User" user "User.Eco2")
		(25 "Edge.Cuts" user "Board Geometry/Outline")
		(27 "Margin" user)
		(31 "F.CrtYd" user "Package Geometry/Place Bound Top")
		(29 "B.CrtYd" user "Package Geometry/Place Bound Bottom")
		(35 "F.Fab" user "Ref Des/Assembly Top")
		(33 "B.Fab" user "Ref Des/Assembly Bottom")
	)
	(footprint ""
		(layer "F.Cu")
		(at 463.343498 -43.221148 180)
		(property "Reference" "R4070"
			(at 0 0 180)
			(layer "F.SilkS")
			(hide yes)
			(effects
				(font
					(size 1.27 1.27)
				)
			)
		)
		(property "Value" ""
			(at 0 0 180)
			(layer "F.Fab")
			(effects
				(font
					(size 1.27 1.27)
				)
			)
		)
		(duplicate_pad_numbers_are_jumpers no)
		(fp_line
			(start 0.7874 0.4064)
			(end -0.7874 0.4064)
			(stroke
				(width 0.1524)
				(type default)
			)
			(layer "F.SilkS")
		)
		(fp_line
			(start 0.7874 -0.4064)
			(end 0.7874 0.4064)
			(stroke
				(width 0.1524)
				(type default)
			)
			(layer "F.SilkS")
		)
		(fp_line
			(start -0.7874 0.4064)
			(end -0.7874 -0.4064)
			(stroke
				(width 0.1524)
				(type default)
			)
			(layer "F.SilkS")
		)
		(fp_line
			(start -0.7874 -0.4064)
			(end 0.7874 -0.4064)
			(stroke
				(width 0.1524)
				(type default)
			)
			(layer "F.SilkS")
		)
		(fp_line
			(start 0.67945 0.3048)
			(end 0.120396 0.3048)
			(stroke
				(width 0.1)
				(type default)
			)
			(layer "F.Fab")
		)
		(fp_line
			(start 0.67945 -0.3048)
			(end 0.67945 0.3048)
			(stroke
				(width 0.1)
				(type default)
			)
			(layer "F.Fab")
		)
		(fp_line
			(start 0.12065 -0.2794)
			(end 0.12065 -0.3048)
			(stroke
				(width 0.1)
				(type default)
			)
			(layer "F.Fab")
		)
		(fp_line
			(start 0.12065 -0.3048)
			(end 0.67945 -0.3048)
			(stroke
				(width 0.1)
				(type default)
			)
			(layer "F.Fab")
		)
		(fp_line
			(start 0.120396 0.3048)
			(end 0.120396 0.2794)
			(stroke
				(width 0.1)
				(type default)
			)
			(layer "F.Fab")
		)
		(fp_line
			(start 0.120396 0.2794)
			(end -0.12065 0.2794)
			(stroke
				(width 0.1)
				(type default)
			)
			(layer "F.Fab")
		)
		(fp_line
			(start -0.12065 0.3048)
			(end -0.67945 0.3048)
			(stroke
				(width 0.1)
				(type default)
			)
			(layer "F.Fab")
		)
		(fp_line
			(start -0.12065 0.2794)
			(end -0.12065 0.3048)
			(stroke
				(width 0.1)
				(type default)
			)
			(layer "F.Fab")
		)
		(fp_line
			(start -0.12065 -0.2794)
			(end 0.12065 -0.2794)
			(stroke
				(width 0.1)
				(type default)
			)
			(layer "F.Fab")
		)
		(fp_line
			(start -0.12065 -0.305054)
			(end -0.12065 -0.2794)
			(stroke
				(width 0.1)
				(type default)
			)
			(layer "F.Fab")
		)
		(fp_line
			(start -0.67945 0.3048)
			(end -0.67945 -0.305054)
			(stroke
				(width 0.1)
				(type default)
			)
			(layer "F.Fab")
		)
		(fp_line
			(start -0.67945 -0.305054)
			(end -0.12065 -0.305054)
			(stroke
				(width 0.1)
				(type default)
			)
			(layer "F.Fab")
		)
		(pad "1" smd circle
			(at -0.40005 0 180)
			(size 0 0)
			(layers "F.Cu" "F.Mask" "F.Paste")
			(net "P12V_AUX")
		)
		(pad "2" smd circle
			(at 0.40005 0 180)
			(size 0 0)
			(layers "F.Cu" "F.Mask" "F.Paste")
			(net "P3V3_OCP_1_EN_G")
		)
	)
	(footprint ""
		(layer "F.Cu")
		(at 69.02196 -57.094628)
		(property "Reference" "PU207"
			(at -5.23748 1.086612 0)
			(unlocked yes)
			(layer "F.SilkS")
			(effects
				(font
					(size 0.7874 0.5842)
					(thickness 0.1524)
				)
			)
		)
		(property "Value" ""
			(at 0 0 0)
			(layer "F.Fab")
			(effects
				(font
					(size 1.27 1.27)
				)
			)
		)
		(duplicate_pad_numbers_are_jumpers no)
		(fp_line
			(start -1.239774 -1.495298)
			(end 1.239774 -1.495298)
			(stroke
				(width 0.1524)
				(type default)
			)
			(layer "F.SilkS")
		)
		(fp_line
			(start -1.239774 1.495298)
			(end -1.239774 -1.495298)
			(stroke
				(width 0.1524)
				(type default)
			)
			(layer "F.SilkS")
		)
		(fp_line
			(start 1.239774 -1.495298)
			(end 1.239774 1.495298)
			(stroke
				(width 0.1524)
				(type default)
			)
			(layer "F.SilkS")
		)
		(fp_line
			(start 1.239774 1.495298)
			(end -1.239774 1.495298)
			(stroke
				(width 0.1524)
				(type default)
			)
			(layer "F.SilkS")
		)
		(fp_poly
			(pts
				(xy -2.525014 -1.62814) (xy -1.509014 -1.12014) (xy -2.525014 -0.61214)
			)
			(stroke
				(width 0)
				(type default)
			)
			(fill yes)
			(layer "F.SilkS")
		)
		(fp_line
			(start -0.8001 -1.050036)
			(end 0.8001 -1.050036)
			(stroke
				(width 0.1)
				(type default)
			)
			(layer "F.Fab")
		)
		(fp_line
			(start -0.8001 1.050036)
			(end -0.8001 -1.050036)
			(stroke
				(width 0.1)
				(type default)
			)
			(layer "F.Fab")
		)
		(fp_line
			(start 0.8001 -1.050036)
			(end 0.8001 1.050036)
			(stroke
				(width 0.1)
				(type default)
			)
			(layer "F.Fab")
		)
		(fp_line
			(start 0.8001 1.050036)
			(end -0.8001 1.050036)
			(stroke
				(width 0.1)
				(type default)
			)
			(layer "F.Fab")
		)
		(fp_poly
			(pts
				(xy -2.458974 -0.508) (xy -2.458974 0.508) (xy -1.442974 0)
			)
			(stroke
				(width 0)
				(type default)
			)
			(fill yes)
			(layer "F.Fab")
		)
		(pad "1_2" smd circle
			(at -0.374904 0 90)
			(size 0 0)
			(layers "F.Cu" "F.Mask" "F.Paste")
			(net "P3V3_AUX")
		)
		(pad "3" smd rect
			(at -0.499872 0.999998)
			(size 0.254 0.7112)
			(layers "F.Cu" "F.Mask" "F.Paste")
			(net "GND")
		)
		(pad "4" smd rect
			(at 0 0.999998)
			(size 0.254 0.7112)
			(layers "F.Cu" "F.Mask" "F.Paste")
			(net "P3V3_OCP_ILIMIT_2")
		)
		(pad "5" smd rect
			(at 0.499872 0.999998)
			(size 0.254 0.7112)
			(layers "F.Cu" "F.Mask" "F.Paste")
			(net "P3V3_OCP_MODE_2")
		)
		(pad "6_7" smd circle
			(at 0.374904 0 270)
			(size 0 0)
			(layers "F.Cu" "F.Mask" "F.Paste")
			(net "P3V3_OCP_V3_2_R")
		)
		(pad "8" smd rect
			(at 0.499872 -0.999998)
			(size 0.254 0.7112)
			(layers "F.Cu" "F.Mask" "F.Paste")
			(net "P3V3_OCP_GATE_PU207_2")
		)
		(pad "9" smd rect
			(at 0 -0.999998)
			(size 0.254 0.7112)
			(layers "F.Cu" "F.Mask" "F.Paste")
			(net "P3V3_OCP_EN_2")
		)
		(pad "10" smd rect
			(at -0.499872 -0.999998)
			(size 0.254 0.7112)
			(layers "F.Cu" "F.Mask" "F.Paste")
			(net "P3V3_OCP_DVDT_2")
		)
	)
	(footprint ""
		(layer "F.Cu")
		(at 77.784198 -408.517344 -90)
		(property "Reference" "C691"
			(at 0 0 270)
			(layer "F.SilkS")
			(hide yes)
			(effects
				(font
					(size 1.27 1.27)
				)
			)
		)
		(property "Value" ""
			(at 0 0 270)
			(layer "F.Fab")
			(effects
				(font
					(size 1.27 1.27)
				)
			)
		)
		(duplicate_pad_numbers_are_jumpers no)
		(fp_line
			(start -0.299974 0.150114)
			(end -0.299974 -0.150114)
			(stroke
				(width 0.1)
				(type default)
			)
			(layer "F.Fab")
		)
		(fp_line
			(start 0.299974 0.150114)
			(end -0.299974 0.150114)
			(stroke
				(width 0.1)
				(type default)
			)
			(layer "F.Fab")
		)
		(fp_line
			(start -0.299974 -0.150114)
			(end 0.299974 -0.150114)
			(stroke
				(width 0.1)
				(type default)
			)
			(layer "F.Fab")
		)
		(fp_line
			(start 0.299974 -0.150114)
			(end 0.299974 0.150114)
			(stroke
				(width 0.1)
				(type default)
			)
			(layer "F.Fab")
		)
		(pad "1" smd rect
			(at -0.2667 0 270)
			(size 0.3048 0.381)
			(layers "F.Cu" "F.Mask" "F.Paste")
			(net "P5E_CPU1_PE4_TX_C_DP<9>")
		)
		(pad "2" smd rect
			(at 0.2667 0 270)
			(size 0.3048 0.381)
			(layers "F.Cu" "F.Mask" "F.Paste")
			(net "P5E_CPU1_PE4_TX_DP<9>")
		)
	)
	(footprint ""
		(layer "F.Cu")
		(at 432.636676 -94.938342)
		(property "Reference" "R3603"
			(at 0 0 0)
			(layer "F.SilkS")
			(hide yes)
			(effects
				(font
					(size 1.27 1.27)
				)
			)
		)
		(property "Value" ""
			(at 0 0 0)
			(layer "F.Fab")
			(effects
				(font
					(size 1.27 1.27)
				)
			)
		)
		(duplicate_pad_numbers_are_jumpers no)
		(fp_line
			(start -0.7874 -0.4064)
			(end 0.7874 -0.4064)
			(stroke
				(width 0.1524)
				(type default)
			)
			(layer "F.SilkS")
		)
		(fp_line
			(start -0.7874 0.4064)
			(end -0.7874 -0.4064)
			(stroke
				(width 0.1524)
				(type default)
			)
			(layer "F.SilkS")
		)
		(fp_line
			(start 0.7874 -0.4064)
			(end 0.7874 0.4064)
			(stroke
				(width 0.1524)
				(type default)
			)
			(layer "F.SilkS")
		)
		(fp_line
			(start 0.7874 0.4064)
			(end -0.7874 0.4064)
			(stroke
				(width 0.1524)
				(type default)
			)
			(layer "F.SilkS")
		)
		(fp_line
			(start -0.67945 -0.305054)
			(end -0.12065 -0.305054)
			(stroke
				(width 0.1)
				(type default)
			)
			(layer "F.Fab")
		)
		(fp_line
			(start -0.67945 0.3048)
			(end -0.67945 -0.305054)
			(stroke
				(width 0.1)
				(type default)
			)
			(layer "F.Fab")
		)
		(fp_line
			(start -0.12065 -0.305054)
			(end -0.12065 -0.2794)
			(stroke
				(width 0.1)
				(type default)
			)
			(layer "F.Fab")
		)
		(fp_line
			(start -0.12065 -0.2794)
			(end 0.12065 -0.2794)
			(stroke
				(width 0.1)
				(type default)
			)
			(layer "F.Fab")
		)
		(fp_line
			(start -0.12065 0.2794)
			(end -0.12065 0.3048)
			(stroke
				(width 0.1)
				(type default)
			)
			(layer "F.Fab")
		)
		(fp_line
			(start -0.12065 0.3048)
			(end -0.67945 0.3048)
			(stroke
				(width 0.1)
				(type default)
			)
			(layer "F.Fab")
		)
		(fp_line
			(start 0.120396 0.2794)
			(end -0.12065 0.2794)
			(stroke
				(width 0.1)
				(type default)
			)
			(layer "F.Fab")
		)
		(fp_line
			(start 0.120396 0.3048)
			(end 0.120396 0.2794)
			(stroke
				(width 0.1)
				(type default)
			)
			(layer "F.Fab")
		)
		(fp_line
			(start 0.12065 -0.3048)
			(end 0.67945 -0.3048)
			(stroke
				(width 0.1)
				(type default)
			)
			(layer "F.Fab")
		)
		(fp_line
			(start 0.12065 -0.2794)
			(end 0.12065 -0.3048)
			(stroke
				(width 0.1)
				(type default)
			)
			(layer "F.Fab")
		)
		(fp_line
			(start 0.67945 -0.3048)
			(end 0.67945 0.3048)
			(stroke
				(width 0.1)
				(type default)
			)
			(layer "F.Fab")
		)
		(fp_line
			(start 0.67945 0.3048)
			(end 0.120396 0.3048)
			(stroke
				(width 0.1)
				(type default)
			)
			(layer "F.Fab")
		)
		(pad "1" smd circle
			(at -0.40005 0)
			(size 0 0)
			(layers "F.Cu" "F.Mask" "F.Paste")
			(net "P3V3_OCP_SFF")
		)
		(pad "2" smd circle
			(at 0.40005 0)
			(size 0 0)
			(layers "F.Cu" "F.Mask" "F.Paste")
			(net "VSENSE_P3V3_INA230_1_INN")
		)
	)
	(footprint ""
		(layer "F.Cu")
		(at 24.069802 -407.890218 180)
		(property "Reference" "R3428"
			(at 0 0 180)
			(layer "F.SilkS")
			(hide yes)
			(effects
				(font
					(size 1.27 1.27)
				)
			)
		)
		(property "Value" ""
			(at 0 0 180)
			(layer "F.Fab")
			(effects
				(font
					(size 1.27 1.27)
				)
			)
		)
		(duplicate_pad_numbers_are_jumpers no)
		(fp_line
			(start 0.7874 0.4064)
			(end -0.7874 0.4064)
			(stroke
				(width 0.1524)
				(type default)
			)
			(layer "F.SilkS")
		)
		(fp_line
			(start 0.7874 -0.4064)
			(end 0.7874 0.4064)
			(stroke
				(width 0.1524)
				(type default)
			)
			(layer "F.SilkS")
		)
		(fp_line
			(start -0.7874 0.4064)
			(end -0.7874 -0.4064)
			(stroke
				(width 0.1524)
				(type default)
			)
			(layer "F.SilkS")
		)
		(fp_line
			(start -0.7874 -0.4064)
			(end 0.7874 -0.4064)
			(stroke
				(width 0.1524)
				(type default)
			)
			(layer "F.SilkS")
		)
		(fp_line
			(start 0.67945 0.3048)
			(end 0.120396 0.3048)
			(stroke
				(width 0.1)
				(type default)
			)
			(layer "F.Fab")
		)
		(fp_line
			(start 0.67945 -0.3048)
			(end 0.67945 0.3048)
			(stroke
				(width 0.1)
				(type default)
			)
			(layer "F.Fab")
		)
		(fp_line
			(start 0.12065 -0.2794)
			(end 0.12065 -0.3048)
			(stroke
				(width 0.1)
				(type default)
			)
			(layer "F.Fab")
		)
		(fp_line
			(start 0.12065 -0.3048)
			(end 0.67945 -0.3048)
			(stroke
				(width 0.1)
				(type default)
			)
			(layer "F.Fab")
		)
		(fp_line
			(start 0.120396 0.3048)
			(end 0.120396 0.2794)
			(stroke
				(width 0.1)
				(type default)
			)
			(layer "F.Fab")
		)
		(fp_line
			(start 0.120396 0.2794)
			(end -0.12065 0.2794)
			(stroke
				(width 0.1)
				(type default)
			)
			(layer "F.Fab")
		)
		(fp_line
			(start -0.12065 0.3048)
			(end -0.67945 0.3048)
			(stroke
				(width 0.1)
				(type default)
			)
			(layer "F.Fab")
		)
		(fp_line
			(start -0.12065 0.2794)
			(end -0.12065 0.3048)
			(stroke
				(width 0.1)
				(type default)
			)
			(layer "F.Fab")
		)
		(fp_line
			(start -0.12065 -0.2794)
			(end 0.12065 -0.2794)
			(stroke
				(width 0.1)
				(type default)
			)
			(layer "F.Fab")
		)
		(fp_line
			(start -0.12065 -0.305054)
			(end -0.12065 -0.2794)
			(stroke
				(width 0.1)
				(type default)
			)
			(layer "F.Fab")
		)
		(fp_line
			(start -0.67945 0.3048)
			(end -0.67945 -0.305054)
			(stroke
				(width 0.1)
				(type default)
			)
			(layer "F.Fab")
		)
		(fp_line
			(start -0.67945 -0.305054)
			(end -0.12065 -0.305054)
			(stroke
				(width 0.1)
				(type default)
			)
			(layer "F.Fab")
		)
		(pad "1" smd circle
			(at -0.40005 0 180)
			(size 0 0)
			(layers "F.Cu" "F.Mask" "F.Paste")
			(net "GPU_FPGA_THERM_OVERT_N")
		)
		(pad "2" smd circle
			(at 0.40005 0 180)
			(size 0 0)
			(layers "F.Cu" "F.Mask" "F.Paste")
			(net "GND")
		)
	)
	(footprint ""
		(layer "F.Cu")
		(at 39.643558 -100.49129)
		(property "Reference" "U193"
			(at -1.797558 3.525012 0)
			(unlocked yes)
			(layer "F.SilkS")
			(effects
				(font
					(size 0.7874 0.5842)
					(thickness 0.1524)
				)
				(justify left)
			)
		)
		(property "Value" ""
			(at 0 0 0)
			(layer "F.Fab")
			(effects
				(font
					(size 1.27 1.27)
				)
			)
		)
		(duplicate_pad_numbers_are_jumpers no)
		(fp_line
			(start -1.715516 -2.489962)
			(end -1.715516 2.489962)
			(stroke
				(width 0.1524)
				(type default)
			)
			(layer "F.SilkS")
		)
		(fp_line
			(start -1.715516 2.489962)
			(end 1.715516 2.489962)
			(stroke
				(width 0.1524)
				(type default)
			)
			(layer "F.SilkS")
		)
		(fp_line
			(start -1.092962 -2.489962)
			(end -1.715516 -2.489962)
			(stroke
				(width 0.1524)
				(type default)
			)
			(layer "F.SilkS")
		)
		(fp_line
			(start 0 -1.397)
			(end -1.092962 -2.489962)
			(stroke
				(width 0.1524)
				(type default)
			)
			(layer "F.SilkS")
		)
		(fp_line
			(start 1.092962 -2.489962)
			(end 0 -1.397)
			(stroke
				(width 0.1524)
				(type default)
			)
			(layer "F.SilkS")
		)
		(fp_line
			(start 1.715516 -2.489962)
			(end 1.092962 -2.489962)
			(stroke
				(width 0.1524)
				(type default)
			)
			(layer "F.SilkS")
		)
		(fp_line
			(start 1.715516 2.489962)
			(end 1.715516 -2.489962)
			(stroke
				(width 0.1524)
				(type default)
			)
			(layer "F.SilkS")
		)
		(fp_poly
			(pts
				(xy -2.187956 -3.79984) (xy -2.695956 -2.78384) (xy -3.203956 -3.79984)
			)
			(stroke
				(width 0)
				(type default)
			)
			(fill yes)
			(layer "F.SilkS")
		)
		(fp_line
			(start -1.994916 -2.489962)
			(end -1.994916 2.489962)
			(stroke
				(width 0.1)
				(type default)
			)
			(layer "F.Fab")
		)
		(fp_line
			(start -1.994916 2.489962)
			(end 1.994916 2.489962)
			(stroke
				(width 0.1)
				(type default)
			)
			(layer "F.Fab")
		)
		(fp_line
			(start 1.994916 -2.489962)
			(end -1.994916 -2.489962)
			(stroke
				(width 0.1)
				(type default)
			)
			(layer "F.Fab")
		)
		(fp_line
			(start 1.994916 2.489962)
			(end 1.994916 -2.489962)
			(stroke
				(width 0.1)
				(type default)
			)
			(layer "F.Fab")
		)
		(fp_poly
			(pts
				(xy -4.699 -2.7305) (xy -4.699 -1.7145) (xy -3.683 -2.2225)
			)
			(stroke
				(width 0)
				(type default)
			)
			(fill yes)
			(layer "F.Fab")
		)
		(pad "1" smd rect
			(at -2.655062 -2.2225 90)
			(size 0.381 1.6002)
			(layers "F.Cu" "F.Mask" "F.Paste")
			(net "MAX11617_VREF_R")
		)
		(pad "2" smd rect
			(at -2.655062 -1.5875 90)
			(size 0.381 1.6002)
			(layers "F.Cu" "F.Mask" "F.Paste")
			(net "GND")
		)
		(pad "3" smd rect
			(at -2.655062 -0.9525 90)
			(size 0.381 1.6002)
			(layers "F.Cu" "F.Mask" "F.Paste")
			(net "GND")
		)
		(pad "4" smd rect
			(at -2.655062 -0.3175 90)
			(size 0.381 1.6002)
			(layers "F.Cu" "F.Mask" "F.Paste")
			(net "GND")
		)
		(pad "5" smd rect
			(at -2.655062 0.3175 90)
			(size 0.381 1.6002)
			(layers "F.Cu" "F.Mask" "F.Paste")
			(net "P12V_AUX_ADC_MAM")
		)
		(pad "6" smd rect
			(at -2.655062 0.9525 90)
			(size 0.381 1.6002)
			(layers "F.Cu" "F.Mask" "F.Paste")
			(net "P12V_OCP_SFF_ISENSE_MAM")
		)
		(pad "7" smd rect
			(at -2.655062 1.5875 90)
			(size 0.381 1.6002)
			(layers "F.Cu" "F.Mask" "F.Paste")
			(net "P12V_OCP_V3_2_ISENSE_MAM")
		)
		(pad "8" smd rect
			(at -2.655062 2.2225 90)
			(size 0.381 1.6002)
			(layers "F.Cu" "F.Mask" "F.Paste")
			(net "P5V_ADC_MAM")
		)
		(pad "9" smd rect
			(at 2.655062 2.2225 90)
			(size 0.381 1.6002)
			(layers "F.Cu" "F.Mask" "F.Paste")
			(net "P3V3_ADC_MAM")
		)
		(pad "10" smd rect
			(at 2.655062 1.5875 90)
			(size 0.381 1.6002)
			(layers "F.Cu" "F.Mask" "F.Paste")
			(net "P3V3_AUX_ADC_MAM")
		)
		(pad "11" smd rect
			(at 2.655062 0.9525 90)
			(size 0.381 1.6002)
			(layers "F.Cu" "F.Mask" "F.Paste")
			(net "P3V3_PDB_AUX_ADC_MAM")
		)
		(pad "12" smd rect
			(at 2.655062 0.3175 90)
			(size 0.381 1.6002)
			(layers "F.Cu" "F.Mask" "F.Paste")
			(net "P12V_E1S_0_ISENSE_MAM")
		)
		(pad "13" smd rect
			(at 2.655062 -0.3175 90)
			(size 0.381 1.6002)
			(layers "F.Cu" "F.Mask" "F.Paste")
			(net "SMB_SEN_MAM_3V3AUX_SCL")
		)
		(pad "14" smd rect
			(at 2.655062 -0.9525 90)
			(size 0.381 1.6002)
			(layers "F.Cu" "F.Mask" "F.Paste")
			(net "SMB_SEN_MAM_3V3AUX_SDA")
		)
		(pad "15" smd rect
			(at 2.655062 -1.5875 90)
			(size 0.381 1.6002)
			(layers "F.Cu" "F.Mask" "F.Paste")
			(net "GND")
		)
		(pad "16" smd rect
			(at 2.655062 -2.2225 90)
			(size 0.381 1.6002)
			(layers "F.Cu" "F.Mask" "F.Paste")
			(net "P3V3_MAX11617_VDD")
		)
	)
)
